# T6G (Grand Teton) — schematic netlist excerpt (pin names and nets, part order shuffled) for the footprints in the layout excerpt that follows; sources: Cadence DE-HDL packaged netlist, KiCad conversion of 04192023_DAF0TMB3IC0_F0TG_MB_C_brd_V02_OCP.brd

R8035  Q_RES  4.7K 5% EMPTY  pkg 0402LF  page 153 : A = P1V8_AUX ; B = ESPI_CPU0_ALERT_N
R3579  Q_RES  10 1% CHIP  pkg 0402LF  page 237 : A = P12V_SCM ; B = VSENSE_P12V_INA230_5_INN
C113  Q_CAP  100UF 4V 20% X6S  pkg C0805  page 323 : A = P1V8_CPU1_RT_1D ; B = GND

(kicad_pcb
	(version 20260206)
	(generator "pcbnew")
	(generator_version "10.0")
	(general
		(thickness 1.6)
		(legacy_teardrops no)
	)
	(paper "A4")
	(title_block
		(title "04192023_DAF0TMB3IC0_F0TG_MB_C_brd_V02_OCP.brd")
		(comment 1 "Grand Teton / footprints 8058-8060 of 8354")
	)
	(layers
		(0 "F.Cu" signal "TOP")
		(4 "In1.Cu" signal "GND")
		(6 "In2.Cu" signal "IN1")
		(8 "In3.Cu" signal "GND1")
		(10 "In4.Cu" signal "IN2")
		(12 "In5.Cu" signal "GND2")
		(14 "In6.Cu" signal "IN3")
		(16 "In7.Cu" signal "GND3")
		(18 "In8.Cu" signal "VCC")
		(20 "In9.Cu" signal "VCC1")
		(22 "In10.Cu" signal "GND4")
		(24 "In11.Cu" signal "IN4")
		(26 "In12.Cu" signal "GND5")
		(28 "In13.Cu" signal "IN5")
		(30 "In14.Cu" signal "GND6")
		(32 "In15.Cu" signal "IN6")
		(34 "In16.Cu" signal "GND7")
		(2 "B.Cu" signal "BOTTOM")
		(9 "F.Adhes" user "F.Adhesive")
		(11 "B.Adhes" user "B.Adhesive")
		(13 "F.Paste" user "Package Geometry/Pastemask Top")
		(15 "B.Paste" user "Package Geometry/Pastemask Bottom")
		(5 "F.SilkS" user "Ref Des/Silkscreen Top")
		(7 "B.SilkS" user "Ref Des/Silkscreen Bottom")
		(1 "F.Mask" user "Board Geometry/Soldermask Top")
		(3 "B.Mask" user "Board Geometry/Soldermask Bottom")
		(17 "Dwgs.User" user "User.Drawings")
		(19 "Cmts.User" user "User.Comments")
		(21 "Eco1.User" user "User.Eco1")
		(23 "Eco2.User" user "User.Eco2")
		(25 "Edge.Cuts" user "Board Geometry/Outline")
		(27 "Margin" user)
		(31 "F.CrtYd" user "Package Geometry/Place Bound Top")
		(29 "B.CrtYd" user "Package Geometry/Place Bound Bottom")
		(35 "F.Fab" user "Ref Des/Assembly Top")
		(33 "B.Fab" user "Ref Des/Assembly Bottom")
	)
	(footprint ""
		(layer "B.Cu")
		(at 189.879224 -145.585434)
		(property "Reference" "R8035"
			(at 0 0 0)
			(layer "B.SilkS")
			(hide yes)
			(effects
				(font
					(size 1.27 1.27)
				)
				(justify mirror)
			)
		)
		(property "Value" ""
			(at 0 0 0)
			(layer "B.Fab")
			(effects
				(font
					(size 1.27 1.27)
				)
				(justify mirror)
			)
		)
		(duplicate_pad_numbers_are_jumpers no)
		(fp_line
			(start -0.7874 -0.4064)
			(end -0.7874 0.4064)
			(stroke
				(width 0.1524)
				(type default)
			)
			(layer "B.SilkS")
		)
		(fp_line
			(start -0.7874 0.4064)
			(end 0.7874 0.4064)
			(stroke
				(width 0.1524)
				(type default)
			)
			(layer "B.SilkS")
		)
		(fp_line
			(start 0.7874 -0.4064)
			(end -0.7874 -0.4064)
			(stroke
				(width 0.1524)
				(type default)
			)
			(layer "B.SilkS")
		)
		(fp_line
			(start 0.7874 0.4064)
			(end 0.7874 -0.4064)
			(stroke
				(width 0.1524)
				(type default)
			)
			(layer "B.SilkS")
		)
		(fp_line
			(start -0.67945 -0.3048)
			(end -0.67945 0.3048)
			(stroke
				(width 0.1)
				(type default)
			)
			(layer "B.Fab")
		)
		(fp_line
			(start -0.67945 0.3048)
			(end -0.120396 0.3048)
			(stroke
				(width 0.1)
				(type default)
			)
			(layer "B.Fab")
		)
		(fp_line
			(start -0.12065 -0.3048)
			(end -0.67945 -0.3048)
			(stroke
				(width 0.1)
				(type default)
			)
			(layer "B.Fab")
		)
		(fp_line
			(start -0.12065 -0.2794)
			(end -0.12065 -0.3048)
			(stroke
				(width 0.1)
				(type default)
			)
			(layer "B.Fab")
		)
		(fp_line
			(start -0.120396 0.2794)
			(end 0.12065 0.2794)
			(stroke
				(width 0.1)
				(type default)
			)
			(layer "B.Fab")
		)
		(fp_line
			(start -0.120396 0.3048)
			(end -0.120396 0.2794)
			(stroke
				(width 0.1)
				(type default)
			)
			(layer "B.Fab")
		)
		(fp_line
			(start 0.12065 -0.305054)
			(end 0.12065 -0.2794)
			(stroke
				(width 0.1)
				(type default)
			)
			(layer "B.Fab")
		)
		(fp_line
			(start 0.12065 -0.2794)
			(end -0.12065 -0.2794)
			(stroke
				(width 0.1)
				(type default)
			)
			(layer "B.Fab")
		)
		(fp_line
			(start 0.12065 0.2794)
			(end 0.12065 0.3048)
			(stroke
				(width 0.1)
				(type default)
			)
			(layer "B.Fab")
		)
		(fp_line
			(start 0.12065 0.3048)
			(end 0.67945 0.3048)
			(stroke
				(width 0.1)
				(type default)
			)
			(layer "B.Fab")
		)
		(fp_line
			(start 0.67945 -0.305054)
			(end 0.12065 -0.305054)
			(stroke
				(width 0.1)
				(type default)
			)
			(layer "B.Fab")
		)
		(fp_line
			(start 0.67945 0.3048)
			(end 0.67945 -0.305054)
			(stroke
				(width 0.1)
				(type default)
			)
			(layer "B.Fab")
		)
		(pad "1" smd circle
			(at 0.40005 0 180)
			(size 0 0)
			(layers "B.Cu" "B.Mask" "B.Paste")
			(net "P1V8_AUX")
		)
		(pad "2" smd circle
			(at -0.40005 0 180)
			(size 0 0)
			(layers "B.Cu" "B.Mask" "B.Paste")
			(net "ESPI_CPU0_ALERT_N")
		)
	)
	(footprint ""
		(layer "B.Cu")
		(at 203.33208 -35.372548 180)
		(property "Reference" "R3579"
			(at 0 0 0)
			(layer "B.SilkS")
			(hide yes)
			(effects
				(font
					(size 1.27 1.27)
				)
				(justify mirror)
			)
		)
		(property "Value" ""
			(at 0 0 0)
			(layer "B.Fab")
			(effects
				(font
					(size 1.27 1.27)
				)
				(justify mirror)
			)
		)
		(duplicate_pad_numbers_are_jumpers no)
		(fp_line
			(start 0.7874 0.4064)
			(end 0.7874 -0.4064)
			(stroke
				(width 0.1524)
				(type default)
			)
			(layer "B.SilkS")
		)
		(fp_line
			(start 0.7874 -0.4064)
			(end -0.7874 -0.4064)
			(stroke
				(width 0.1524)
				(type default)
			)
			(layer "B.SilkS")
		)
		(fp_line
			(start -0.7874 0.4064)
			(end 0.7874 0.4064)
			(stroke
				(width 0.1524)
				(type default)
			)
			(layer "B.SilkS")
		)
		(fp_line
			(start -0.7874 -0.4064)
			(end -0.7874 0.4064)
			(stroke
				(width 0.1524)
				(type default)
			)
			(layer "B.SilkS")
		)
		(fp_line
			(start 0.67945 0.3048)
			(end 0.67945 -0.305054)
			(stroke
				(width 0.1)
				(type default)
			)
			(layer "B.Fab")
		)
		(fp_line
			(start 0.67945 -0.305054)
			(end 0.12065 -0.305054)
			(stroke
				(width 0.1)
				(type default)
			)
			(layer "B.Fab")
		)
		(fp_line
			(start 0.12065 0.3048)
			(end 0.67945 0.3048)
			(stroke
				(width 0.1)
				(type default)
			)
			(layer "B.Fab")
		)
		(fp_line
			(start 0.12065 0.2794)
			(end 0.12065 0.3048)
			(stroke
				(width 0.1)
				(type default)
			)
			(layer "B.Fab")
		)
		(fp_line
			(start 0.12065 -0.2794)
			(end -0.12065 -0.2794)
			(stroke
				(width 0.1)
				(type default)
			)
			(layer "B.Fab")
		)
		(fp_line
			(start 0.12065 -0.305054)
			(end 0.12065 -0.2794)
			(stroke
				(width 0.1)
				(type default)
			)
			(layer "B.Fab")
		)
		(fp_line
			(start -0.120396 0.3048)
			(end -0.120396 0.2794)
			(stroke
				(width 0.1)
				(type default)
			)
			(layer "B.Fab")
		)
		(fp_line
			(start -0.120396 0.2794)
			(end 0.12065 0.2794)
			(stroke
				(width 0.1)
				(type default)
			)
			(layer "B.Fab")
		)
		(fp_line
			(start -0.12065 -0.2794)
			(end -0.12065 -0.3048)
			(stroke
				(width 0.1)
				(type default)
			)
			(layer "B.Fab")
		)
		(fp_line
			(start -0.12065 -0.3048)
			(end -0.67945 -0.3048)
			(stroke
				(width 0.1)
				(type default)
			)
			(layer "B.Fab")
		)
		(fp_line
			(start -0.67945 0.3048)
			(end -0.120396 0.3048)
			(stroke
				(width 0.1)
				(type default)
			)
			(layer "B.Fab")
		)
		(fp_line
			(start -0.67945 -0.3048)
			(end -0.67945 0.3048)
			(stroke
				(width 0.1)
				(type default)
			)
			(layer "B.Fab")
		)
		(pad "1" smd circle
			(at 0.40005 0)
			(size 0 0)
			(layers "B.Cu" "B.Mask" "B.Paste")
			(net "P12V_SCM")
		)
		(pad "2" smd circle
			(at -0.40005 0)
			(size 0 0)
			(layers "B.Cu" "B.Mask" "B.Paste")
			(net "VSENSE_P12V_INA230_5_INN")
		)
	)
	(footprint ""
		(layer "B.Cu")
		(at 70.645528 -387.084062 -90)
		(property "Reference" "C113"
			(at 0 0 90)
			(layer "B.SilkS")
			(hide yes)
			(effects
				(font
					(size 1.27 1.27)
				)
				(justify mirror)
			)
		)
		(property "Value" ""
			(at 0 0 90)
			(layer "B.Fab")
			(effects
				(font
					(size 1.27 1.27)
				)
				(justify mirror)
			)
		)
		(duplicate_pad_numbers_are_jumpers no)
		(fp_line
			(start -1.524 0.762)
			(end 1.524 0.762)
			(stroke
				(width 0.1524)
				(type default)
			)
			(layer "B.SilkS")
		)
		(fp_line
			(start 1.524 0.762)
			(end 1.524 -0.762)
			(stroke
				(width 0.1524)
				(type default)
			)
			(layer "B.SilkS")
		)
		(fp_line
			(start -1.524 -0.762)
			(end -1.524 0.762)
			(stroke
				(width 0.1524)
				(type default)
			)
			(layer "B.SilkS")
		)
		(fp_line
			(start 1.524 -0.762)
			(end -1.524 -0.762)
			(stroke
				(width 0.1524)
				(type default)
			)
			(layer "B.SilkS")
		)
		(fp_line
			(start -1.1049 0.724916)
			(end -1.1049 -0.724916)
			(stroke
				(width 0.1)
				(type default)
			)
			(layer "B.Fab")
		)
		(fp_line
			(start 1.1049 0.724916)
			(end -1.1049 0.724916)
			(stroke
				(width 0.1)
				(type default)
			)
			(layer "B.Fab")
		)
		(fp_line
			(start -1.1049 -0.724916)
			(end 1.1049 -0.724916)
			(stroke
				(width 0.1)
				(type default)
			)
			(layer "B.Fab")
		)
		(fp_line
			(start 1.1049 -0.724916)
			(end 1.1049 0.724916)
			(stroke
				(width 0.1)
				(type default)
			)
			(layer "B.Fab")
		)
		(pad "1" smd rect
			(at 0.889 0 270)
			(size 1.016 1.27)
			(layers "B.Cu" "B.Mask" "B.Paste")
			(net "P1V8_CPU1_RT_1D")
		)
		(pad "2" smd rect
			(at -0.889 0 270)
			(size 1.016 1.27)
			(layers "B.Cu" "B.Mask" "B.Paste")
			(net "GND")
		)
	)
)
